(kicad_pcb
	(version 20260206)
	(generator "pcbnew")
	(generator_version "10.0")
	(general
		(thickness 1.6)
		(legacy_teardrops no)
	)
	(paper "A4")
	(title_block
		(title "Wiwynn_Tioga_Pass_MB.brd")
		(comment 1 "Tioga Pass / footprints 4045-4051 of 4770")
	)
	(layers
		(0 "F.Cu" signal "TOP")
		(4 "In1.Cu" signal "L2GND")
		(6 "In2.Cu" signal "L3")
		(8 "In3.Cu" signal "L4GND")
		(10 "In4.Cu" signal "L5")
		(12 "In5.Cu" signal "L6GND")
		(14 "In6.Cu" signal "L7VCC")
		(16 "In7.Cu" signal "L8VCC")
		(18 "In8.Cu" signal "L9GND")
		(20 "In9.Cu" signal "L10")
		(22 "In10.Cu" signal "L11GND")
		(24 "In11.Cu" signal "L12")
		(26 "In12.Cu" signal "L13GND")
		(2 "B.Cu" signal "BOTTOM")
		(9 "F.Adhes" user "F.Adhesive")
		(11 "B.Adhes" user "B.Adhesive")
		(13 "F.Paste" user "Package Geometry/Pastemask Top")
		(15 "B.Paste" user "Package Geometry/Pastemask Bottom")
		(5 "F.SilkS" user "Ref Des/Silkscreen Top")
		(7 "B.SilkS" user "Ref Des/Silkscreen Bottom")
		(1 "F.Mask" user "Board Geometry/Soldermask Top")
		(3 "B.Mask" user "Board Geometry/Soldermask Bottom")
		(17 "Dwgs.User" user "User.Drawings")
		(19 "Cmts.User" user "User.Comments")
		(21 "Eco1.User" user "User.Eco1")
		(23 "Eco2.User" user "User.Eco2")
		(25 "Edge.Cuts" user "Board Geometry/Outline")
		(27 "Margin" user)
		(31 "F.CrtYd" user "Package Geometry/Place Bound Top")
		(29 "B.CrtYd" user "Package Geometry/Place Bound Bottom")
		(35 "F.Fab" user "Ref Des/Assembly Top")
		(33 "B.Fab" user "Ref Des/Assembly Bottom")
	)
	(footprint ""
		(layer "B.Cu")
		(at 13.97 -40.513 -90)
		(property "Reference" "R9T1"
			(at 0 0 90)
			(layer "B.SilkS")
			(hide yes)
			(effects
				(font
					(size 1.27 1.27)
				)
				(justify mirror)
			)
		)
		(property "Value" ""
			(at 0 0 90)
			(layer "B.Fab")
			(effects
				(font
					(size 1.27 1.27)
				)
				(justify mirror)
			)
		)
		(duplicate_pad_numbers_are_jumpers no)
		(fp_poly
			(pts
				(xy 0.2794 -0.1016) (xy -0.2794 -0.1016) (xy -0.2794 0.9906) (xy 0.2794 0.9906)
			)
			(stroke
				(width 0)
				(type default)
			)
			(fill no)
			(layer "B.CrtYd")
		)
		(fp_line
			(start -0.2794 0.9906)
			(end -0.2794 -0.1016)
			(stroke
				(width 0.1)
				(type default)
			)
			(layer "B.Fab")
		)
		(fp_line
			(start 0.2794 0.9906)
			(end -0.2794 0.9906)
			(stroke
				(width 0.1)
				(type default)
			)
			(layer "B.Fab")
		)
		(fp_line
			(start -0.2794 -0.1016)
			(end 0.2794 -0.1016)
			(stroke
				(width 0.1)
				(type default)
			)
			(layer "B.Fab")
		)
		(fp_line
			(start 0.2794 -0.1016)
			(end 0.2794 0.9906)
			(stroke
				(width 0.1)
				(type default)
			)
			(layer "B.Fab")
		)
		(pad "1" smd rect
			(at 0 0 90)
			(size 0.508 0.508)
			(layers "B.Cu" "B.Mask" "B.Paste")
			(net "FAN_PWM_OUT_SYS0_R")
		)
		(pad "2" smd rect
			(at 0 0.889 90)
			(size 0.508 0.508)
			(layers "B.Cu" "B.Mask" "B.Paste")
			(net "FAN_PWM_OUT_SYS0_R1")
		)
		(zone
			(layer "B.Cu")
			(hatch none 0.5)
			(connect_pads
				(clearance 0)
			)
			(min_thickness 0.25)
			(keepout
				(tracks not_allowed)
				(vias allowed)
				(pads allowed)
				(copperpour not_allowed)
				(footprints allowed)
			)
			(placement
				(enabled no)
				(sheetname "")
			)
			(fill
				(thermal_gap 0.5)
				(thermal_bridge_width 0.5)
				(island_removal_mode 0)
			)
			(polygon
				(pts
					(xy 13.335 -40.259) (xy 13.335 -40.767) (xy 13.716 -40.767) (xy 13.716 -40.259)
				)
			)
		)
		(zone
			(layer "B.Cu")
			(hatch none 0.5)
			(connect_pads
				(clearance 0)
			)
			(min_thickness 0.25)
			(keepout
				(tracks allowed)
				(vias not_allowed)
				(pads allowed)
				(copperpour not_allowed)
				(footprints allowed)
			)
			(placement
				(enabled no)
				(sheetname "")
			)
			(fill
				(thermal_gap 0.5)
				(thermal_bridge_width 0.5)
				(island_removal_mode 0)
			)
			(polygon
				(pts
					(xy 13.716 -40.259) (xy 13.716 -40.767) (xy 13.335 -40.767) (xy 13.335 -40.259)
				)
			)
		)
	)
	(footprint ""
		(layer "B.Cu")
		(at 386.93725 -113.45545)
		(property "Reference" "C3M43"
			(at 0 0 0)
			(layer "B.SilkS")
			(hide yes)
			(effects
				(font
					(size 1.27 1.27)
				)
				(justify mirror)
			)
		)
		(property "Value" ""
			(at 0 0 0)
			(layer "B.Fab")
			(effects
				(font
					(size 1.27 1.27)
				)
				(justify mirror)
			)
		)
		(duplicate_pad_numbers_are_jumpers no)
		(fp_rect
			(start 0.2794 0.9144)
			(end -0.2794 -0.1143)
			(stroke
				(width 0)
				(type default)
			)
			(fill no)
			(layer "B.CrtYd")
		)
		(fp_line
			(start -0.2794 -0.1143)
			(end -0.2794 0.9144)
			(stroke
				(width 0.1)
				(type default)
			)
			(layer "B.Fab")
		)
		(fp_line
			(start -0.2794 0.9144)
			(end 0.2794 0.9144)
			(stroke
				(width 0.1)
				(type default)
			)
			(layer "B.Fab")
		)
		(fp_line
			(start 0.2794 -0.1143)
			(end -0.2794 -0.1143)
			(stroke
				(width 0.1)
				(type default)
			)
			(layer "B.Fab")
		)
		(fp_line
			(start 0.2794 0.9144)
			(end 0.2794 -0.1143)
			(stroke
				(width 0.1)
				(type default)
			)
			(layer "B.Fab")
		)
		(pad "1" smd custom
			(at 0 0 270)
			(size 0.10414 0.10414)
			(layers "B.Cu" "B.Mask" "B.Paste")
			(net "P1V05_PCH_STBY")
			(options
				(clearance outline)
				(anchor circle)
			)
			(primitives
				(gr_poly
					(pts
						(xy -0.20828 -0.08636) (xy -0.20828 0.08636) (xy -0.08636 0.20828) (xy 0.086614 0.20828) (xy 0.20828 0.086614)
						(xy 0.20828 -0.08636) (xy 0.08636 -0.20828) (xy -0.08636 -0.20828)
					)
					(width 0)
					(fill yes)
				)
			)
		)
		(pad "2" smd custom
			(at 0 0.8001 270)
			(size 0.10414 0.10414)
			(layers "B.Cu" "B.Mask" "B.Paste")
			(net "GND")
			(options
				(clearance outline)
				(anchor circle)
			)
			(primitives
				(gr_poly
					(pts
						(xy -0.20828 -0.08636) (xy -0.20828 0.08636) (xy -0.08636 0.20828) (xy 0.086614 0.20828) (xy 0.20828 0.086614)
						(xy 0.20828 -0.08636) (xy 0.08636 -0.20828) (xy -0.08636 -0.20828)
					)
					(width 0)
					(fill yes)
				)
			)
		)
		(zone
			(layer "B.Cu")
			(hatch none 0.5)
			(connect_pads
				(clearance 0)
			)
			(min_thickness 0.25)
			(keepout
				(tracks allowed)
				(vias not_allowed)
				(pads allowed)
				(copperpour not_allowed)
				(footprints allowed)
			)
			(placement
				(enabled no)
				(sheetname "")
			)
			(fill
				(thermal_gap 0.5)
				(thermal_bridge_width 0.5)
				(island_removal_mode 0)
			)
			(polygon
				(pts
					(xy 387.02488 -113.2459) (xy 387.02488 -112.8649) (xy 386.84962 -112.8649) (xy 386.849366 -113.2459)
				)
			)
		)
		(zone
			(layer "B.Cu")
			(hatch none 0.5)
			(connect_pads
				(clearance 0)
			)
			(min_thickness 0.25)
			(keepout
				(tracks not_allowed)
				(vias allowed)
				(pads allowed)
				(copperpour not_allowed)
				(footprints allowed)
			)
			(placement
				(enabled no)
				(sheetname "")
			)
			(fill
				(thermal_gap 0.5)
				(thermal_bridge_width 0.5)
				(island_removal_mode 0)
			)
			(polygon
				(pts
					(xy 387.02488 -113.2459) (xy 387.02488 -112.8649) (xy 386.84962 -112.8649) (xy 386.849366 -113.2459)
				)
			)
		)
	)
	(footprint ""
		(layer "B.Cu")
		(at 401.272756 -111.636556)
		(property "Reference" "C2N6"
			(at 0 0 0)
			(layer "B.SilkS")
			(hide yes)
			(effects
				(font
					(size 1.27 1.27)
				)
				(justify mirror)
			)
		)
		(property "Value" ""
			(at 0 0 0)
			(layer "B.Fab")
			(effects
				(font
					(size 1.27 1.27)
				)
				(justify mirror)
			)
		)
		(duplicate_pad_numbers_are_jumpers no)
		(fp_poly
			(pts
				(xy 0.4953 -0.2032) (xy -0.4953 -0.2032) (xy -0.4953 1.6002) (xy 0.4953 1.6002)
			)
			(stroke
				(width 0)
				(type default)
			)
			(fill no)
			(layer "B.CrtYd")
		)
		(fp_line
			(start -0.4953 -0.2032)
			(end -0.4953 1.6002)
			(stroke
				(width 0.1)
				(type default)
			)
			(layer "B.Fab")
		)
		(fp_line
			(start -0.4953 1.6002)
			(end 0.4953 1.6002)
			(stroke
				(width 0.1)
				(type default)
			)
			(layer "B.Fab")
		)
		(fp_line
			(start 0.4953 -0.2032)
			(end -0.4953 -0.2032)
			(stroke
				(width 0.1)
				(type default)
			)
			(layer "B.Fab")
		)
		(fp_line
			(start 0.4953 1.6002)
			(end 0.4953 -0.2032)
			(stroke
				(width 0.1)
				(type default)
			)
			(layer "B.Fab")
		)
		(pad "1" smd rect
			(at 0 0 180)
			(size 0.762 0.889)
			(layers "B.Cu" "B.Mask" "B.Paste")
			(net "P1V05_PCH_STBY_KR_PLL")
		)
		(pad "2" smd rect
			(at 0 1.397 180)
			(size 0.762 0.889)
			(layers "B.Cu" "B.Mask" "B.Paste")
			(net "GND")
		)
		(zone
			(layer "B.Cu")
			(hatch none 0.5)
			(connect_pads
				(clearance 0)
			)
			(min_thickness 0.25)
			(keepout
				(tracks not_allowed)
				(vias allowed)
				(pads allowed)
				(copperpour not_allowed)
				(footprints allowed)
			)
			(placement
				(enabled no)
				(sheetname "")
			)
			(fill
				(thermal_gap 0.5)
				(thermal_bridge_width 0.5)
				(island_removal_mode 0)
			)
			(polygon
				(pts
					(xy 401.653756 -111.192056) (xy 400.891756 -111.192056) (xy 400.891756 -110.684056) (xy 401.653756 -110.684056)
				)
			)
		)
	)
	(footprint ""
		(layer "B.Cu")
		(at 336.042 -94.234 90)
		(property "Reference" "C3N38"
			(at 0.73533 -3.937 0)
			(unlocked yes)
			(layer "B.SilkS")
			(effects
				(font
					(size 0.7874 0.5842)
					(thickness 0.1524)
				)
				(justify mirror)
			)
		)
		(property "Value" ""
			(at 0 0 90)
			(layer "B.Fab")
			(effects
				(font
					(size 1.27 1.27)
				)
				(justify mirror)
			)
		)
		(duplicate_pad_numbers_are_jumpers no)
		(fp_line
			(start 2.563114 -1.616456)
			(end 2.563114 1.633728)
			(stroke
				(width 0.1524)
				(type default)
			)
			(layer "B.SilkS")
		)
		(fp_line
			(start 1.6002 -1.616456)
			(end 2.563114 -1.616456)
			(stroke
				(width 0.1524)
				(type default)
			)
			(layer "B.SilkS")
		)
		(fp_line
			(start -1.6002 -1.616456)
			(end -2.504948 -1.616456)
			(stroke
				(width 0.1524)
				(type default)
			)
			(layer "B.SilkS")
		)
		(fp_line
			(start -2.504948 -1.616456)
			(end -2.504948 1.633728)
			(stroke
				(width 0.1524)
				(type default)
			)
			(layer "B.SilkS")
		)
		(fp_line
			(start 2.563114 1.633728)
			(end 1.6002 1.633728)
			(stroke
				(width 0.1524)
				(type default)
			)
			(layer "B.SilkS")
		)
		(fp_line
			(start -2.504948 1.633728)
			(end -1.6002 1.633728)
			(stroke
				(width 0.1524)
				(type default)
			)
			(layer "B.SilkS")
		)
		(fp_line
			(start 2.286 7.366)
			(end 2.286 1.632712)
			(stroke
				(width 0.1524)
				(type default)
			)
			(layer "B.SilkS")
		)
		(fp_line
			(start 2.286 7.366)
			(end 1.60147 7.366)
			(stroke
				(width 0.1524)
				(type default)
			)
			(layer "B.SilkS")
		)
		(fp_line
			(start -2.286 7.366)
			(end -2.286 1.63195)
			(stroke
				(width 0.1524)
				(type default)
			)
			(layer "B.SilkS")
		)
		(fp_line
			(start -2.286 7.366)
			(end -1.600708 7.366)
			(stroke
				(width 0.1524)
				(type default)
			)
			(layer "B.SilkS")
		)
		(fp_rect
			(start 2.286 7.366)
			(end -2.286 -0.254)
			(stroke
				(width 0)
				(type default)
			)
			(fill no)
			(layer "B.CrtYd")
		)
		(fp_line
			(start 2.286 -0.254)
			(end -2.286 -0.254)
			(stroke
				(width 0.1)
				(type default)
			)
			(layer "B.Fab")
		)
		(fp_line
			(start -2.286 -0.254)
			(end -2.286 7.366)
			(stroke
				(width 0.1)
				(type default)
			)
			(layer "B.Fab")
		)
		(fp_line
			(start 2.286 7.366)
			(end 2.286 -0.254)
			(stroke
				(width 0.1)
				(type default)
			)
			(layer "B.Fab")
		)
		(fp_line
			(start -2.286 7.366)
			(end 2.286 7.366)
			(stroke
				(width 0.1)
				(type default)
			)
			(layer "B.Fab")
		)
		(pad "1" smd rect
			(at 0 0 270)
			(size 2.54 3.048)
			(layers "B.Cu" "B.Mask" "B.Paste")
			(net "PVCCIO_CPU0")
		)
		(pad "2" smd rect
			(at 0 7.112 270)
			(size 2.54 3.048)
			(layers "B.Cu" "B.Mask" "B.Paste")
			(net "GND")
		)
	)
	(footprint ""
		(layer "B.Cu")
		(at 375.9708 -154.457146)
		(property "Reference" "C3L12"
			(at 0 0 0)
			(layer "B.SilkS")
			(hide yes)
			(effects
				(font
					(size 1.27 1.27)
				)
				(justify mirror)
			)
		)
		(property "Value" ""
			(at 0 0 0)
			(layer "B.Fab")
			(effects
				(font
					(size 1.27 1.27)
				)
				(justify mirror)
			)
		)
		(duplicate_pad_numbers_are_jumpers no)
		(fp_poly
			(pts
				(xy 0.7239 -0.2159) (xy -0.7239 -0.2159) (xy -0.7239 1.9939) (xy 0.7239 1.9939)
			)
			(stroke
				(width 0)
				(type default)
			)
			(fill no)
			(layer "B.CrtYd")
		)
		(fp_line
			(start -0.7239 -0.2159)
			(end 0.7239 -0.2159)
			(stroke
				(width 0.1)
				(type default)
			)
			(layer "B.Fab")
		)
		(fp_line
			(start -0.7239 1.9939)
			(end -0.7239 -0.2159)
			(stroke
				(width 0.1)
				(type default)
			)
			(layer "B.Fab")
		)
		(fp_line
			(start 0.7239 -0.2159)
			(end 0.7239 1.9939)
			(stroke
				(width 0.1)
				(type default)
			)
			(layer "B.Fab")
		)
		(fp_line
			(start 0.7239 1.9939)
			(end -0.7239 1.9939)
			(stroke
				(width 0.1)
				(type default)
			)
			(layer "B.Fab")
		)
		(pad "1" smd rect
			(at 0 0 180)
			(size 1.27 1.016)
			(layers "B.Cu" "B.Mask" "B.Paste")
			(net "VR_FET_SW_P12V_STBY_PVDDQ_DEF")
		)
		(pad "2" smd rect
			(at 0 1.778 180)
			(size 1.27 1.016)
			(layers "B.Cu" "B.Mask" "B.Paste")
			(net "GND")
		)
		(zone
			(layer "B.Cu")
			(hatch none 0.5)
			(connect_pads
				(clearance 0)
			)
			(min_thickness 0.25)
			(keepout
				(tracks not_allowed)
				(vias allowed)
				(pads allowed)
				(copperpour not_allowed)
				(footprints allowed)
			)
			(placement
				(enabled no)
				(sheetname "")
			)
			(fill
				(thermal_gap 0.5)
				(thermal_bridge_width 0.5)
				(island_removal_mode 0)
			)
			(polygon
				(pts
					(xy 376.6058 -153.949146) (xy 375.3358 -153.949146) (xy 375.3358 -153.187146) (xy 376.6058 -153.187146)
				)
			)
		)
	)
	(footprint ""
		(layer "B.Cu")
		(at 329.438 -8.382)
		(property "Reference" "R4U3"
			(at 0 0 0)
			(layer "B.SilkS")
			(hide yes)
			(effects
				(font
					(size 1.27 1.27)
				)
				(justify mirror)
			)
		)
		(property "Value" ""
			(at 0 0 0)
			(layer "B.Fab")
			(effects
				(font
					(size 1.27 1.27)
				)
				(justify mirror)
			)
		)
		(duplicate_pad_numbers_are_jumpers no)
		(fp_poly
			(pts
				(xy 0.2794 -0.1016) (xy -0.2794 -0.1016) (xy -0.2794 0.9906) (xy 0.2794 0.9906)
			)
			(stroke
				(width 0)
				(type default)
			)
			(fill no)
			(layer "B.CrtYd")
		)
		(fp_line
			(start -0.2794 -0.1016)
			(end 0.2794 -0.1016)
			(stroke
				(width 0.1)
				(type default)
			)
			(layer "B.Fab")
		)
		(fp_line
			(start -0.2794 0.9906)
			(end -0.2794 -0.1016)
			(stroke
				(width 0.1)
				(type default)
			)
			(layer "B.Fab")
		)
		(fp_line
			(start 0.2794 -0.1016)
			(end 0.2794 0.9906)
			(stroke
				(width 0.1)
				(type default)
			)
			(layer "B.Fab")
		)
		(fp_line
			(start 0.2794 0.9906)
			(end -0.2794 0.9906)
			(stroke
				(width 0.1)
				(type default)
			)
			(layer "B.Fab")
		)
		(pad "1" smd rect
			(at 0 0 180)
			(size 0.508 0.508)
			(layers "B.Cu" "B.Mask" "B.Paste")
			(net "PVPP_ABC")
		)
		(pad "2" smd rect
			(at 0 0.889 180)
			(size 0.508 0.508)
			(layers "B.Cu" "B.Mask" "B.Paste")
			(net "FM_DIMM_EVENT_FET")
		)
		(zone
			(layer "B.Cu")
			(hatch none 0.5)
			(connect_pads
				(clearance 0)
			)
			(min_thickness 0.25)
			(keepout
				(tracks allowed)
				(vias not_allowed)
				(pads allowed)
				(copperpour not_allowed)
				(footprints allowed)
			)
			(placement
				(enabled no)
				(sheetname "")
			)
			(fill
				(thermal_gap 0.5)
				(thermal_bridge_width 0.5)
				(island_removal_mode 0)
			)
			(polygon
				(pts
					(xy 329.692 -8.128) (xy 329.184 -8.128) (xy 329.184 -7.747) (xy 329.692 -7.747)
				)
			)
		)
		(zone
			(layer "B.Cu")
			(hatch none 0.5)
			(connect_pads
				(clearance 0)
			)
			(min_thickness 0.25)
			(keepout
				(tracks not_allowed)
				(vias allowed)
				(pads allowed)
				(copperpour not_allowed)
				(footprints allowed)
			)
			(placement
				(enabled no)
				(sheetname "")
			)
			(fill
				(thermal_gap 0.5)
				(thermal_bridge_width 0.5)
				(island_removal_mode 0)
			)
			(polygon
				(pts
					(xy 329.692 -7.747) (xy 329.184 -7.747) (xy 329.184 -8.128) (xy 329.692 -8.128)
				)
			)
		)
	)
	(footprint ""
		(layer "B.Cu")
		(at 434.6575 -18.288 -90)
		(property "Reference" "R1U34"
			(at 0 0 90)
			(layer "B.SilkS")
			(hide yes)
			(effects
				(font
					(size 1.27 1.27)
				)
				(justify mirror)
			)
		)
		(property "Value" ""
			(at 0 0 90)
			(layer "B.Fab")
			(effects
				(font
					(size 1.27 1.27)
				)
				(justify mirror)
			)
		)
		(duplicate_pad_numbers_are_jumpers no)
		(fp_poly
			(pts
				(xy 0.2794 -0.1016) (xy -0.2794 -0.1016) (xy -0.2794 0.9906) (xy 0.2794 0.9906)
			)
			(stroke
				(width 0)
				(type default)
			)
			(fill no)
			(layer "B.CrtYd")
		)
		(fp_line
			(start -0.2794 0.9906)
			(end -0.2794 -0.1016)
			(stroke
				(width 0.1)
				(type default)
			)
			(layer "B.Fab")
		)
		(fp_line
			(start 0.2794 0.9906)
			(end -0.2794 0.9906)
			(stroke
				(width 0.1)
				(type default)
			)
			(layer "B.Fab")
		)
		(fp_line
			(start -0.2794 -0.1016)
			(end 0.2794 -0.1016)
			(stroke
				(width 0.1)
				(type default)
			)
			(layer "B.Fab")
		)
		(fp_line
			(start 0.2794 -0.1016)
			(end 0.2794 0.9906)
			(stroke
				(width 0.1)
				(type default)
			)
			(layer "B.Fab")
		)
		(pad "1" smd rect
			(at 0 0 90)
			(size 0.508 0.508)
			(layers "B.Cu" "B.Mask" "B.Paste")
			(net "H_CPU1_MEMKLM_MEMHOT_LVT3_K_N")
		)
		(pad "2" smd rect
			(at 0 0.889 90)
			(size 0.508 0.508)
			(layers "B.Cu" "B.Mask" "B.Paste")
			(net "H_CPU1_MEMKLM_MEMHOT_LVT3_N")
		)
		(zone
			(layer "B.Cu")
			(hatch none 0.5)
			(connect_pads
				(clearance 0)
			)
			(min_thickness 0.25)
			(keepout
				(tracks not_allowed)
				(vias allowed)
				(pads allowed)
				(copperpour not_allowed)
				(footprints allowed)
			)
			(placement
				(enabled no)
				(sheetname "")
			)
			(fill
				(thermal_gap 0.5)
				(thermal_bridge_width 0.5)
				(island_removal_mode 0)
			)
			(polygon
				(pts
					(xy 434.0225 -18.034) (xy 434.0225 -18.542) (xy 434.4035 -18.542) (xy 434.4035 -18.034)
				)
			)
		)
		(zone
			(layer "B.Cu")
			(hatch none 0.5)
			(connect_pads
				(clearance 0)
			)
			(min_thickness 0.25)
			(keepout
				(tracks allowed)
				(vias not_allowed)
				(pads allowed)
				(copperpour not_allowed)
				(footprints allowed)
			)
			(placement
				(enabled no)
				(sheetname "")
			)
			(fill
				(thermal_gap 0.5)
				(thermal_bridge_width 0.5)
				(island_removal_mode 0)
			)
			(polygon
				(pts
					(xy 434.4035 -18.034) (xy 434.4035 -18.542) (xy 434.0225 -18.542) (xy 434.0225 -18.034)
				)
			)
		)
	)
)
